(kicad_pcb
	(version 20260206)
	(generator "pcbnew")
	(generator_version "10.0")
	(general
		(thickness 1.6)
		(legacy_teardrops no)
	)
	(paper "A4")
	(title_block
		(title "04192023_DAF0TMB3IC0_F0TG_MB_C_brd_V02_OCP.brd")
		(comment 1 "Grand Teton / footprints 1709-1716 of 8354")
	)
	(layers
		(0 "F.Cu" signal "TOP")
		(4 "In1.Cu" signal "GND")
		(6 "In2.Cu" signal "IN1")
		(8 "In3.Cu" signal "GND1")
		(10 "In4.Cu" signal "IN2")
		(12 "In5.Cu" signal "GND2")
		(14 "In6.Cu" signal "IN3")
		(16 "In7.Cu" signal "GND3")
		(18 "In8.Cu" signal "VCC")
		(20 "In9.Cu" signal "VCC1")
		(22 "In10.Cu" signal "GND4")
		(24 "In11.Cu" signal "IN4")
		(26 "In12.Cu" signal "GND5")
		(28 "In13.Cu" signal "IN5")
		(30 "In14.Cu" signal "GND6")
		(32 "In15.Cu" signal "IN6")
		(34 "In16.Cu" signal "GND7")
		(2 "B.Cu" signal "BOTTOM")
		(9 "F.Adhes" user "F.Adhesive")
		(11 "B.Adhes" user "B.Adhesive")
		(13 "F.Paste" user "Package Geometry/Pastemask Top")
		(15 "B.Paste" user "Package Geometry/Pastemask Bottom")
		(5 "F.SilkS" user "Ref Des/Silkscreen Top")
		(7 "B.SilkS" user "Ref Des/Silkscreen Bottom")
		(1 "F.Mask" user "Board Geometry/Soldermask Top")
		(3 "B.Mask" user "Board Geometry/Soldermask Bottom")
		(17 "Dwgs.User" user "User.Drawings")
		(19 "Cmts.User" user "User.Comments")
		(21 "Eco1.User" user "User.Eco1")
		(23 "Eco2.User" user "User.Eco2")
		(25 "Edge.Cuts" user "Board Geometry/Outline")
		(27 "Margin" user)
		(31 "F.CrtYd" user "Package Geometry/Place Bound Top")
		(29 "B.CrtYd" user "Package Geometry/Place Bound Bottom")
		(35 "F.Fab" user "Ref Des/Assembly Top")
		(33 "B.Fab" user "Ref Des/Assembly Bottom")
	)
	(footprint ""
		(layer "F.Cu")
		(at 205.24089 -108.545376 180)
		(property "Reference" "R259"
			(at 0 0 180)
			(layer "F.SilkS")
			(hide yes)
			(effects
				(font
					(size 1.27 1.27)
				)
			)
		)
		(property "Value" ""
			(at 0 0 180)
			(layer "F.Fab")
			(effects
				(font
					(size 1.27 1.27)
				)
			)
		)
		(duplicate_pad_numbers_are_jumpers no)
		(fp_line
			(start 0.7874 0.4064)
			(end -0.7874 0.4064)
			(stroke
				(width 0.1524)
				(type default)
			)
			(layer "F.SilkS")
		)
		(fp_line
			(start 0.7874 -0.4064)
			(end 0.7874 0.4064)
			(stroke
				(width 0.1524)
				(type default)
			)
			(layer "F.SilkS")
		)
		(fp_line
			(start -0.7874 0.4064)
			(end -0.7874 -0.4064)
			(stroke
				(width 0.1524)
				(type default)
			)
			(layer "F.SilkS")
		)
		(fp_line
			(start -0.7874 -0.4064)
			(end 0.7874 -0.4064)
			(stroke
				(width 0.1524)
				(type default)
			)
			(layer "F.SilkS")
		)
		(fp_line
			(start 0.67945 0.3048)
			(end 0.120396 0.3048)
			(stroke
				(width 0.1)
				(type default)
			)
			(layer "F.Fab")
		)
		(fp_line
			(start 0.67945 -0.3048)
			(end 0.67945 0.3048)
			(stroke
				(width 0.1)
				(type default)
			)
			(layer "F.Fab")
		)
		(fp_line
			(start 0.12065 -0.2794)
			(end 0.12065 -0.3048)
			(stroke
				(width 0.1)
				(type default)
			)
			(layer "F.Fab")
		)
		(fp_line
			(start 0.12065 -0.3048)
			(end 0.67945 -0.3048)
			(stroke
				(width 0.1)
				(type default)
			)
			(layer "F.Fab")
		)
		(fp_line
			(start 0.120396 0.3048)
			(end 0.120396 0.2794)
			(stroke
				(width 0.1)
				(type default)
			)
			(layer "F.Fab")
		)
		(fp_line
			(start 0.120396 0.2794)
			(end -0.12065 0.2794)
			(stroke
				(width 0.1)
				(type default)
			)
			(layer "F.Fab")
		)
		(fp_line
			(start -0.12065 0.3048)
			(end -0.67945 0.3048)
			(stroke
				(width 0.1)
				(type default)
			)
			(layer "F.Fab")
		)
		(fp_line
			(start -0.12065 0.2794)
			(end -0.12065 0.3048)
			(stroke
				(width 0.1)
				(type default)
			)
			(layer "F.Fab")
		)
		(fp_line
			(start -0.12065 -0.2794)
			(end 0.12065 -0.2794)
			(stroke
				(width 0.1)
				(type default)
			)
			(layer "F.Fab")
		)
		(fp_line
			(start -0.12065 -0.305054)
			(end -0.12065 -0.2794)
			(stroke
				(width 0.1)
				(type default)
			)
			(layer "F.Fab")
		)
		(fp_line
			(start -0.67945 0.3048)
			(end -0.67945 -0.305054)
			(stroke
				(width 0.1)
				(type default)
			)
			(layer "F.Fab")
		)
		(fp_line
			(start -0.67945 -0.305054)
			(end -0.12065 -0.305054)
			(stroke
				(width 0.1)
				(type default)
			)
			(layer "F.Fab")
		)
		(pad "1" smd circle
			(at -0.40005 0 180)
			(size 0 0)
			(layers "F.Cu" "F.Mask" "F.Paste")
			(net "PWRGD_PVDD18_S5_P1")
		)
		(pad "2" smd circle
			(at 0.40005 0 180)
			(size 0 0)
			(layers "F.Cu" "F.Mask" "F.Paste")
			(net "PWRGD_PVDD18_S5_R_P1")
		)
	)
	(footprint ""
		(layer "F.Cu")
		(at 326.125586 -416.899344 -90)
		(property "Reference" "C6515"
			(at 0 0 270)
			(layer "F.SilkS")
			(hide yes)
			(effects
				(font
					(size 1.27 1.27)
				)
			)
		)
		(property "Value" ""
			(at 0 0 270)
			(layer "F.Fab")
			(effects
				(font
					(size 1.27 1.27)
				)
			)
		)
		(duplicate_pad_numbers_are_jumpers no)
		(fp_line
			(start -0.299974 0.150114)
			(end -0.299974 -0.150114)
			(stroke
				(width 0.1)
				(type default)
			)
			(layer "F.Fab")
		)
		(fp_line
			(start 0.299974 0.150114)
			(end -0.299974 0.150114)
			(stroke
				(width 0.1)
				(type default)
			)
			(layer "F.Fab")
		)
		(fp_line
			(start -0.299974 -0.150114)
			(end 0.299974 -0.150114)
			(stroke
				(width 0.1)
				(type default)
			)
			(layer "F.Fab")
		)
		(fp_line
			(start 0.299974 -0.150114)
			(end 0.299974 0.150114)
			(stroke
				(width 0.1)
				(type default)
			)
			(layer "F.Fab")
		)
		(pad "1" smd rect
			(at -0.2667 0 270)
			(size 0.3048 0.381)
			(layers "F.Cu" "F.Mask" "F.Paste")
			(net "P5E_CPU0_P0_TX_BUF_C_DP<7>")
		)
		(pad "2" smd rect
			(at 0.2667 0 270)
			(size 0.3048 0.381)
			(layers "F.Cu" "F.Mask" "F.Paste")
			(net "P5E_CPU0_P0_TX_BUF_DP<7>")
		)
	)
	(footprint ""
		(layer "F.Cu")
		(at 192.47358 -418.155882 90)
		(property "Reference" "U278"
			(at -1.78562 -2.481834 90)
			(unlocked yes)
			(layer "F.SilkS")
			(effects
				(font
					(size 0.7874 0.5842)
					(thickness 0.1524)
				)
				(justify left)
			)
		)
		(property "Value" ""
			(at 0 0 90)
			(layer "F.Fab")
			(effects
				(font
					(size 1.27 1.27)
				)
			)
		)
		(duplicate_pad_numbers_are_jumpers no)
		(fp_line
			(start 1.733296 -1.549908)
			(end 0.660908 -1.549908)
			(stroke
				(width 0.1524)
				(type default)
			)
			(layer "F.SilkS")
		)
		(fp_line
			(start 0.660908 -1.549908)
			(end 0 -0.889)
			(stroke
				(width 0.1524)
				(type default)
			)
			(layer "F.SilkS")
		)
		(fp_line
			(start -0.660908 -1.549908)
			(end -1.733296 -1.549908)
			(stroke
				(width 0.1524)
				(type default)
			)
			(layer "F.SilkS")
		)
		(fp_line
			(start -1.733296 -1.549908)
			(end -1.733296 1.549908)
			(stroke
				(width 0.1524)
				(type default)
			)
			(layer "F.SilkS")
		)
		(fp_line
			(start 0 -0.889)
			(end -0.660908 -1.549908)
			(stroke
				(width 0.1524)
				(type default)
			)
			(layer "F.SilkS")
		)
		(fp_line
			(start 1.733296 1.549908)
			(end 1.733296 -1.549908)
			(stroke
				(width 0.1524)
				(type default)
			)
			(layer "F.SilkS")
		)
		(fp_line
			(start -1.733296 1.549908)
			(end 1.733296 1.549908)
			(stroke
				(width 0.1524)
				(type default)
			)
			(layer "F.SilkS")
		)
		(fp_poly
			(pts
				(xy -2.505202 -1.550416) (xy -2.166366 -1.92913) (xy -1.95707 -1.401064)
			)
			(stroke
				(width 0)
				(type default)
			)
			(fill yes)
			(layer "F.SilkS")
		)
		(fp_line
			(start 0.849884 -1.549908)
			(end -0.849884 -1.549908)
			(stroke
				(width 0.1)
				(type default)
			)
			(layer "F.Fab")
		)
		(fp_line
			(start -0.849884 -1.549908)
			(end -0.849884 1.549908)
			(stroke
				(width 0.1)
				(type default)
			)
			(layer "F.Fab")
		)
		(fp_line
			(start 0.849884 1.549908)
			(end 0.849884 -1.549908)
			(stroke
				(width 0.1)
				(type default)
			)
			(layer "F.Fab")
		)
		(fp_line
			(start -0.849884 1.549908)
			(end 0.849884 1.549908)
			(stroke
				(width 0.1)
				(type default)
			)
			(layer "F.Fab")
		)
		(fp_poly
			(pts
				(xy -2.4384 -1.20396) (xy -2.4384 -0.69596) (xy -1.9304 -0.94996)
			)
			(stroke
				(width 0)
				(type default)
			)
			(fill yes)
			(layer "F.Fab")
		)
		(pad "1" smd rect
			(at -1.199896 -0.94996)
			(size 0.5588 0.8128)
			(layers "F.Cu" "F.Mask" "F.Paste")
			(net "FM_GPU_HSC_EN")
		)
		(pad "2" smd rect
			(at -1.199896 0)
			(size 0.5588 0.8128)
			(layers "F.Cu" "F.Mask" "F.Paste")
			(net "GPU_PRSNT_R")
		)
		(pad "3" smd rect
			(at -1.199896 0.94996)
			(size 0.5588 0.8128)
			(layers "F.Cu" "F.Mask" "F.Paste")
			(net "GND")
		)
		(pad "4" smd rect
			(at 1.199896 0.94996)
			(size 0.5588 0.8128)
			(layers "F.Cu" "F.Mask" "F.Paste")
			(net "FM_GPU_HSC_EN_BUF_R")
		)
		(pad "5" smd rect
			(at 1.199896 -0.94996)
			(size 0.5588 0.8128)
			(layers "F.Cu" "F.Mask" "F.Paste")
			(net "P3V3_AUX")
		)
	)
	(footprint ""
		(layer "F.Cu")
		(at 65.48882 -68.890388)
		(property "Reference" "ME2"
			(at 0 0 0)
			(layer "F.SilkS")
			(hide yes)
			(effects
				(font
					(size 1.27 1.27)
				)
			)
		)
		(property "Value" ""
			(at 0 0 0)
			(layer "F.Fab")
			(effects
				(font
					(size 1.27 1.27)
				)
			)
		)
		(duplicate_pad_numbers_are_jumpers no)
		(fp_rect
			(start 0 0)
			(end 3.3401 -0.5842)
			(stroke
				(width 0)
				(type default)
			)
			(fill yes)
			(layer "F.SilkS")
		)
		(fp_rect
			(start 1.32715 -3.2512)
			(end 2.01295 -3.4417)
			(stroke
				(width 0)
				(type default)
			)
			(fill yes)
			(layer "F.SilkS")
		)
		(fp_poly
			(pts
				(xy -0.070612 -0.681228) (xy -0.197612 -0.820928) (xy 0.852678 -1.91262) (xy 0.728472 -3.29184)
				(xy -0.248412 -4.300728) (xy -0.184912 -4.478528) (xy -0.007112 -4.503928) (xy 0.684022 -3.785616)
				(xy 0.65659 -4.0894) (xy 0.97155 -4.3434) (xy 1.22555 -4.3561) (xy 1.46685 -4.4704) (xy 2.01295 -4.4704)
				(xy 2.15265 -4.4069) (xy 2.44475 -4.191) (xy 2.49555 -4.191) (xy 2.59715 -4.2926) (xy 2.80035 -4.2672)
				(xy 2.88925 -4.1656) (xy 2.88925 -4.029456) (xy 3.345688 -4.503928) (xy 3.523488 -4.478528) (xy 3.586988 -4.300728)
				(xy 2.88925 -3.58013) (xy 2.88925 -3.3147) (xy 2.82575 -3.2385) (xy 2.67335 -3.2385) (xy 2.521966 -1.875282)
				(xy 2.545842 -1.85039)
				(arc
					(start 2.55905 -1.8415)
					(mid 2.648099 -1.766068)
					(end 2.717292 -1.672082)
				)
				(xy 3.536188 -0.820928) (xy 3.409188 -0.681228) (xy 3.244088 -0.693928)
				(arc
					(start 2.737612 -1.216914)
					(mid 2.31728 -0.925553)
					(end 1.86055 -1.1557)
				)
				(xy 0.92075 -1.1557) (xy 0.888492 -1.51384) (xy 0.094488 -0.693928)
			)
			(stroke
				(width 0)
				(type default)
			)
			(fill yes)
			(layer "F.SilkS")
		)
	)
	(footprint ""
		(layer "F.Cu")
		(at 339.254084 -339.40877)
		(property "Reference" "PC134_5"
			(at 0 0 0)
			(layer "F.SilkS")
			(hide yes)
			(effects
				(font
					(size 1.27 1.27)
				)
			)
		)
		(property "Value" ""
			(at 0 0 0)
			(layer "F.Fab")
			(effects
				(font
					(size 1.27 1.27)
				)
			)
		)
		(duplicate_pad_numbers_are_jumpers no)
		(fp_line
			(start -0.7874 -0.4064)
			(end 0.7874 -0.4064)
			(stroke
				(width 0.1524)
				(type default)
			)
			(layer "F.SilkS")
		)
		(fp_line
			(start -0.7874 0.4064)
			(end -0.7874 -0.4064)
			(stroke
				(width 0.1524)
				(type default)
			)
			(layer "F.SilkS")
		)
		(fp_line
			(start 0.7874 -0.4064)
			(end 0.7874 0.4064)
			(stroke
				(width 0.1524)
				(type default)
			)
			(layer "F.SilkS")
		)
		(fp_line
			(start 0.7874 0.4064)
			(end -0.7874 0.4064)
			(stroke
				(width 0.1524)
				(type default)
			)
			(layer "F.SilkS")
		)
		(fp_line
			(start -0.67945 -0.305054)
			(end -0.12065 -0.305054)
			(stroke
				(width 0.1)
				(type default)
			)
			(layer "F.Fab")
		)
		(fp_line
			(start -0.67945 0.3048)
			(end -0.67945 -0.305054)
			(stroke
				(width 0.1)
				(type default)
			)
			(layer "F.Fab")
		)
		(fp_line
			(start -0.12065 -0.305054)
			(end -0.12065 -0.2794)
			(stroke
				(width 0.1)
				(type default)
			)
			(layer "F.Fab")
		)
		(fp_line
			(start -0.12065 -0.2794)
			(end 0.12065 -0.2794)
			(stroke
				(width 0.1)
				(type default)
			)
			(layer "F.Fab")
		)
		(fp_line
			(start -0.12065 0.2794)
			(end -0.12065 0.3048)
			(stroke
				(width 0.1)
				(type default)
			)
			(layer "F.Fab")
		)
		(fp_line
			(start -0.12065 0.3048)
			(end -0.67945 0.3048)
			(stroke
				(width 0.1)
				(type default)
			)
			(layer "F.Fab")
		)
		(fp_line
			(start 0.120396 0.2794)
			(end -0.12065 0.2794)
			(stroke
				(width 0.1)
				(type default)
			)
			(layer "F.Fab")
		)
		(fp_line
			(start 0.120396 0.3048)
			(end 0.120396 0.2794)
			(stroke
				(width 0.1)
				(type default)
			)
			(layer "F.Fab")
		)
		(fp_line
			(start 0.12065 -0.3048)
			(end 0.67945 -0.3048)
			(stroke
				(width 0.1)
				(type default)
			)
			(layer "F.Fab")
		)
		(fp_line
			(start 0.12065 -0.2794)
			(end 0.12065 -0.3048)
			(stroke
				(width 0.1)
				(type default)
			)
			(layer "F.Fab")
		)
		(fp_line
			(start 0.67945 -0.3048)
			(end 0.67945 0.3048)
			(stroke
				(width 0.1)
				(type default)
			)
			(layer "F.Fab")
		)
		(fp_line
			(start 0.67945 0.3048)
			(end 0.120396 0.3048)
			(stroke
				(width 0.1)
				(type default)
			)
			(layer "F.Fab")
		)
		(pad "1" smd circle
			(at -0.40005 0)
			(size 0 0)
			(layers "F.Cu" "F.Mask" "F.Paste")
			(net "SW_P12V_AUX_PVDDCR_CPU1_P0_FLT")
		)
		(pad "2" smd circle
			(at 0.40005 0)
			(size 0 0)
			(layers "F.Cu" "F.Mask" "F.Paste")
			(net "GND")
		)
	)
	(footprint ""
		(layer "F.Cu")
		(at 332.195678 -27.267662 90)
		(property "Reference" "C1567"
			(at 0 0 90)
			(layer "F.SilkS")
			(hide yes)
			(effects
				(font
					(size 1.27 1.27)
				)
			)
		)
		(property "Value" ""
			(at 0 0 90)
			(layer "F.Fab")
			(effects
				(font
					(size 1.27 1.27)
				)
			)
		)
		(duplicate_pad_numbers_are_jumpers no)
		(fp_line
			(start 0.7874 -0.4064)
			(end 0.7874 0.4064)
			(stroke
				(width 0.1524)
				(type default)
			)
			(layer "F.SilkS")
		)
		(fp_line
			(start -0.7874 -0.4064)
			(end 0.7874 -0.4064)
			(stroke
				(width 0.1524)
				(type default)
			)
			(layer "F.SilkS")
		)
		(fp_line
			(start 0.7874 0.4064)
			(end -0.7874 0.4064)
			(stroke
				(width 0.1524)
				(type default)
			)
			(layer "F.SilkS")
		)
		(fp_line
			(start -0.7874 0.4064)
			(end -0.7874 -0.4064)
			(stroke
				(width 0.1524)
				(type default)
			)
			(layer "F.SilkS")
		)
		(fp_line
			(start -0.12065 -0.305054)
			(end -0.12065 -0.2794)
			(stroke
				(width 0.1)
				(type default)
			)
			(layer "F.Fab")
		)
		(fp_line
			(start -0.67945 -0.305054)
			(end -0.12065 -0.305054)
			(stroke
				(width 0.1)
				(type default)
			)
			(layer "F.Fab")
		)
		(fp_line
			(start 0.67945 -0.3048)
			(end 0.67945 0.3048)
			(stroke
				(width 0.1)
				(type default)
			)
			(layer "F.Fab")
		)
		(fp_line
			(start 0.12065 -0.3048)
			(end 0.67945 -0.3048)
			(stroke
				(width 0.1)
				(type default)
			)
			(layer "F.Fab")
		)
		(fp_line
			(start 0.12065 -0.2794)
			(end 0.12065 -0.3048)
			(stroke
				(width 0.1)
				(type default)
			)
			(layer "F.Fab")
		)
		(fp_line
			(start -0.12065 -0.2794)
			(end 0.12065 -0.2794)
			(stroke
				(width 0.1)
				(type default)
			)
			(layer "F.Fab")
		)
		(fp_line
			(start 0.120396 0.2794)
			(end -0.12065 0.2794)
			(stroke
				(width 0.1)
				(type default)
			)
			(layer "F.Fab")
		)
		(fp_line
			(start -0.12065 0.2794)
			(end -0.12065 0.3048)
			(stroke
				(width 0.1)
				(type default)
			)
			(layer "F.Fab")
		)
		(fp_line
			(start 0.67945 0.3048)
			(end 0.120396 0.3048)
			(stroke
				(width 0.1)
				(type default)
			)
			(layer "F.Fab")
		)
		(fp_line
			(start 0.120396 0.3048)
			(end 0.120396 0.2794)
			(stroke
				(width 0.1)
				(type default)
			)
			(layer "F.Fab")
		)
		(fp_line
			(start -0.12065 0.3048)
			(end -0.67945 0.3048)
			(stroke
				(width 0.1)
				(type default)
			)
			(layer "F.Fab")
		)
		(fp_line
			(start -0.67945 0.3048)
			(end -0.67945 -0.305054)
			(stroke
				(width 0.1)
				(type default)
			)
			(layer "F.Fab")
		)
		(pad "1" smd circle
			(at -0.40005 0 90)
			(size 0 0)
			(layers "F.Cu" "F.Mask" "F.Paste")
			(net "P1V5_BAT")
		)
		(pad "2" smd circle
			(at 0.40005 0 90)
			(size 0 0)
			(layers "F.Cu" "F.Mask" "F.Paste")
			(net "GND")
		)
	)
	(footprint ""
		(layer "F.Cu")
		(at 155.575 -114.554)
		(property "Reference" "U24"
			(at -3.103372 -0.603504 0)
			(unlocked yes)
			(layer "F.SilkS")
			(effects
				(font
					(size 0.7874 0.5842)
					(thickness 0.1524)
				)
			)
		)
		(property "Value" ""
			(at 0 0 0)
			(layer "F.Fab")
			(effects
				(font
					(size 1.27 1.27)
				)
			)
		)
		(duplicate_pad_numbers_are_jumpers no)
		(fp_line
			(start -1.949958 -1.610106)
			(end 1.949958 -1.610106)
			(stroke
				(width 0.1524)
				(type default)
			)
			(layer "F.SilkS")
		)
		(fp_line
			(start -1.949958 1.610106)
			(end -1.949958 -1.610106)
			(stroke
				(width 0.1524)
				(type default)
			)
			(layer "F.SilkS")
		)
		(fp_line
			(start 1.949958 -1.560068)
			(end 1.949958 1.610106)
			(stroke
				(width 0.1524)
				(type default)
			)
			(layer "F.SilkS")
		)
		(fp_line
			(start 1.949958 1.610106)
			(end -1.949958 1.610106)
			(stroke
				(width 0.1524)
				(type default)
			)
			(layer "F.SilkS")
		)
		(fp_line
			(start -0.750062 -1.560068)
			(end 0.750062 -1.560068)
			(stroke
				(width 0.1)
				(type default)
			)
			(layer "F.Fab")
		)
		(fp_line
			(start -0.750062 1.560068)
			(end -0.750062 -1.560068)
			(stroke
				(width 0.1)
				(type default)
			)
			(layer "F.Fab")
		)
		(fp_line
			(start 0.750062 -1.560068)
			(end 0.750062 1.560068)
			(stroke
				(width 0.1)
				(type default)
			)
			(layer "F.Fab")
		)
		(fp_line
			(start 0.750062 1.560068)
			(end -0.750062 1.560068)
			(stroke
				(width 0.1)
				(type default)
			)
			(layer "F.Fab")
		)
		(pad "D" smd rect
			(at 1.100074 0 270)
			(size 1.016 1.4224)
			(layers "F.Cu" "F.Mask" "F.Paste")
			(net "HP_LVC3_OCP_SFF_PRSNT2")
		)
		(pad "G" smd rect
			(at -1.100074 -0.94996 270)
			(size 1.016 1.4224)
			(layers "F.Cu" "F.Mask" "F.Paste")
			(net "HP_LVC3_OCP_SFF_PRSNT2_N")
		)
		(pad "S" smd rect
			(at -1.100074 0.94996 270)
			(size 1.016 1.4224)
			(layers "F.Cu" "F.Mask" "F.Paste")
			(net "GND")
		)
	)
	(footprint ""
		(layer "F.Cu")
		(at 343.429844 -383.88163 -90)
		(property "Reference" "C951"
			(at 0 0 270)
			(layer "F.SilkS")
			(hide yes)
			(effects
				(font
					(size 1.27 1.27)
				)
			)
		)
		(property "Value" ""
			(at 0 0 270)
			(layer "F.Fab")
			(effects
				(font
					(size 1.27 1.27)
				)
			)
		)
		(duplicate_pad_numbers_are_jumpers no)
		(fp_line
			(start -0.299974 0.150114)
			(end -0.299974 -0.150114)
			(stroke
				(width 0.1)
				(type default)
			)
			(layer "F.Fab")
		)
		(fp_line
			(start 0.299974 0.150114)
			(end -0.299974 0.150114)
			(stroke
				(width 0.1)
				(type default)
			)
			(layer "F.Fab")
		)
		(fp_line
			(start -0.299974 -0.150114)
			(end 0.299974 -0.150114)
			(stroke
				(width 0.1)
				(type default)
			)
			(layer "F.Fab")
		)
		(fp_line
			(start 0.299974 -0.150114)
			(end 0.299974 0.150114)
			(stroke
				(width 0.1)
				(type default)
			)
			(layer "F.Fab")
		)
		(pad "1" smd rect
			(at -0.2667 0 270)
			(size 0.3048 0.381)
			(layers "F.Cu" "F.Mask" "F.Paste")
			(net "P5E_CPU0_P1_TX_C_DP<7>")
		)
		(pad "2" smd rect
			(at 0.2667 0 270)
			(size 0.3048 0.381)
			(layers "F.Cu" "F.Mask" "F.Paste")
			(net "P5E_CPU0_P1_TX_DP<7>")
		)
	)
)
